(kicad_pcb
	(version 20260206)
	(generator "pcbnew")
	(generator_version "10.0")
	(general
		(thickness 1.6)
		(legacy_teardrops no)
	)
	(paper "A4")
	(title_block
		(title "03242023_DA0F0TMBIJ0_F0T_Motherboard_J_brd_V01_OCP.brd")
		(comment 1 "Grand Teton / footprints 5596-5601 of 6105")
	)
	(layers
		(0 "F.Cu" signal "TOP")
		(4 "In1.Cu" signal "GND")
		(6 "In2.Cu" signal "IN1")
		(8 "In3.Cu" signal "GND1")
		(10 "In4.Cu" signal "IN2")
		(12 "In5.Cu" signal "GND2")
		(14 "In6.Cu" signal "IN3")
		(16 "In7.Cu" signal "GND3")
		(18 "In8.Cu" signal "VCC")
		(20 "In9.Cu" signal "VCC1")
		(22 "In10.Cu" signal "GND4")
		(24 "In11.Cu" signal "IN4")
		(26 "In12.Cu" signal "GND5")
		(28 "In13.Cu" signal "IN5")
		(30 "In14.Cu" signal "GND6")
		(32 "In15.Cu" signal "IN6")
		(34 "In16.Cu" signal "GND7")
		(2 "B.Cu" signal "BOTTOM")
		(9 "F.Adhes" user "F.Adhesive")
		(11 "B.Adhes" user "B.Adhesive")
		(13 "F.Paste" user "Package Geometry/Pastemask Top")
		(15 "B.Paste" user "Package Geometry/Pastemask Bottom")
		(5 "F.SilkS" user "Ref Des/Silkscreen Top")
		(7 "B.SilkS" user "Ref Des/Silkscreen Bottom")
		(1 "F.Mask" user "Board Geometry/Soldermask Top")
		(3 "B.Mask" user "Board Geometry/Soldermask Bottom")
		(17 "Dwgs.User" user "User.Drawings")
		(19 "Cmts.User" user "User.Comments")
		(21 "Eco1.User" user "User.Eco1")
		(23 "Eco2.User" user "User.Eco2")
		(25 "Edge.Cuts" user "Board Geometry/Outline")
		(27 "Margin" user)
		(31 "F.CrtYd" user "Package Geometry/Place Bound Top")
		(29 "B.CrtYd" user "Package Geometry/Place Bound Bottom")
		(35 "F.Fab" user "Ref Des/Assembly Top")
		(33 "B.Fab" user "Ref Des/Assembly Bottom")
	)
	(footprint ""
		(layer "B.Cu")
		(at 71.385684 -188.458856 90)
		(property "Reference" "R59"
			(at 0 0 90)
			(layer "B.SilkS")
			(hide yes)
			(effects
				(font
					(size 1.27 1.27)
				)
				(justify mirror)
			)
		)
		(property "Value" ""
			(at 0 0 90)
			(layer "B.Fab")
			(effects
				(font
					(size 1.27 1.27)
				)
				(justify mirror)
			)
		)
		(duplicate_pad_numbers_are_jumpers no)
		(fp_line
			(start 0.7874 -0.4064)
			(end -0.7874 -0.4064)
			(stroke
				(width 0.1524)
				(type default)
			)
			(layer "B.SilkS")
		)
		(fp_line
			(start -0.7874 -0.4064)
			(end -0.7874 0.4064)
			(stroke
				(width 0.1524)
				(type default)
			)
			(layer "B.SilkS")
		)
		(fp_line
			(start 0.7874 0.4064)
			(end 0.7874 -0.4064)
			(stroke
				(width 0.1524)
				(type default)
			)
			(layer "B.SilkS")
		)
		(fp_line
			(start -0.7874 0.4064)
			(end 0.7874 0.4064)
			(stroke
				(width 0.1524)
				(type default)
			)
			(layer "B.SilkS")
		)
		(fp_line
			(start 0.67945 -0.305054)
			(end 0.12065 -0.305054)
			(stroke
				(width 0.1)
				(type default)
			)
			(layer "B.Fab")
		)
		(fp_line
			(start 0.12065 -0.305054)
			(end 0.12065 -0.2794)
			(stroke
				(width 0.1)
				(type default)
			)
			(layer "B.Fab")
		)
		(fp_line
			(start -0.12065 -0.3048)
			(end -0.67945 -0.3048)
			(stroke
				(width 0.1)
				(type default)
			)
			(layer "B.Fab")
		)
		(fp_line
			(start -0.67945 -0.3048)
			(end -0.67945 0.3048)
			(stroke
				(width 0.1)
				(type default)
			)
			(layer "B.Fab")
		)
		(fp_line
			(start 0.12065 -0.2794)
			(end -0.12065 -0.2794)
			(stroke
				(width 0.1)
				(type default)
			)
			(layer "B.Fab")
		)
		(fp_line
			(start -0.12065 -0.2794)
			(end -0.12065 -0.3048)
			(stroke
				(width 0.1)
				(type default)
			)
			(layer "B.Fab")
		)
		(fp_line
			(start 0.12065 0.2794)
			(end 0.12065 0.3048)
			(stroke
				(width 0.1)
				(type default)
			)
			(layer "B.Fab")
		)
		(fp_line
			(start -0.120396 0.2794)
			(end 0.12065 0.2794)
			(stroke
				(width 0.1)
				(type default)
			)
			(layer "B.Fab")
		)
		(fp_line
			(start 0.67945 0.3048)
			(end 0.67945 -0.305054)
			(stroke
				(width 0.1)
				(type default)
			)
			(layer "B.Fab")
		)
		(fp_line
			(start 0.12065 0.3048)
			(end 0.67945 0.3048)
			(stroke
				(width 0.1)
				(type default)
			)
			(layer "B.Fab")
		)
		(fp_line
			(start -0.120396 0.3048)
			(end -0.120396 0.2794)
			(stroke
				(width 0.1)
				(type default)
			)
			(layer "B.Fab")
		)
		(fp_line
			(start -0.67945 0.3048)
			(end -0.120396 0.3048)
			(stroke
				(width 0.1)
				(type default)
			)
			(layer "B.Fab")
		)
		(pad "1" smd circle
			(at 0.40005 0 270)
			(size 0 0)
			(layers "B.Cu" "B.Mask" "B.Paste")
			(net "SVID_CLK1_CPU1")
		)
		(pad "2" smd circle
			(at -0.40005 0 270)
			(size 0 0)
			(layers "B.Cu" "B.Mask" "B.Paste")
			(net "SVID_CLK1_CPU1_R")
		)
	)
	(footprint ""
		(layer "B.Cu")
		(at 354.446586 -235.916724)
		(property "Reference" "C1362"
			(at 0 0 0)
			(layer "B.SilkS")
			(hide yes)
			(effects
				(font
					(size 1.27 1.27)
				)
				(justify mirror)
			)
		)
		(property "Value" ""
			(at 0 0 0)
			(layer "B.Fab")
			(effects
				(font
					(size 1.27 1.27)
				)
				(justify mirror)
			)
		)
		(duplicate_pad_numbers_are_jumpers no)
		(fp_line
			(start -0.7874 -0.4064)
			(end -0.7874 0.4064)
			(stroke
				(width 0.1524)
				(type default)
			)
			(layer "B.SilkS")
		)
		(fp_line
			(start -0.7874 0.4064)
			(end 0.7874 0.4064)
			(stroke
				(width 0.1524)
				(type default)
			)
			(layer "B.SilkS")
		)
		(fp_line
			(start 0.7874 -0.4064)
			(end -0.7874 -0.4064)
			(stroke
				(width 0.1524)
				(type default)
			)
			(layer "B.SilkS")
		)
		(fp_line
			(start 0.7874 0.4064)
			(end 0.7874 -0.4064)
			(stroke
				(width 0.1524)
				(type default)
			)
			(layer "B.SilkS")
		)
		(fp_line
			(start -0.67945 -0.3048)
			(end -0.67945 0.3048)
			(stroke
				(width 0.1)
				(type default)
			)
			(layer "B.Fab")
		)
		(fp_line
			(start -0.67945 0.3048)
			(end -0.120396 0.3048)
			(stroke
				(width 0.1)
				(type default)
			)
			(layer "B.Fab")
		)
		(fp_line
			(start -0.12065 -0.3048)
			(end -0.67945 -0.3048)
			(stroke
				(width 0.1)
				(type default)
			)
			(layer "B.Fab")
		)
		(fp_line
			(start -0.12065 -0.2794)
			(end -0.12065 -0.3048)
			(stroke
				(width 0.1)
				(type default)
			)
			(layer "B.Fab")
		)
		(fp_line
			(start -0.120396 0.2794)
			(end 0.12065 0.2794)
			(stroke
				(width 0.1)
				(type default)
			)
			(layer "B.Fab")
		)
		(fp_line
			(start -0.120396 0.3048)
			(end -0.120396 0.2794)
			(stroke
				(width 0.1)
				(type default)
			)
			(layer "B.Fab")
		)
		(fp_line
			(start 0.12065 -0.305054)
			(end 0.12065 -0.2794)
			(stroke
				(width 0.1)
				(type default)
			)
			(layer "B.Fab")
		)
		(fp_line
			(start 0.12065 -0.2794)
			(end -0.12065 -0.2794)
			(stroke
				(width 0.1)
				(type default)
			)
			(layer "B.Fab")
		)
		(fp_line
			(start 0.12065 0.2794)
			(end 0.12065 0.3048)
			(stroke
				(width 0.1)
				(type default)
			)
			(layer "B.Fab")
		)
		(fp_line
			(start 0.12065 0.3048)
			(end 0.67945 0.3048)
			(stroke
				(width 0.1)
				(type default)
			)
			(layer "B.Fab")
		)
		(fp_line
			(start 0.67945 -0.305054)
			(end 0.12065 -0.305054)
			(stroke
				(width 0.1)
				(type default)
			)
			(layer "B.Fab")
		)
		(fp_line
			(start 0.67945 0.3048)
			(end 0.67945 -0.305054)
			(stroke
				(width 0.1)
				(type default)
			)
			(layer "B.Fab")
		)
		(pad "1" smd circle
			(at 0.40005 0 180)
			(size 0 0)
			(layers "B.Cu" "B.Mask" "B.Paste")
			(net "PVNN_MAIN_CPU0")
		)
		(pad "2" smd circle
			(at -0.40005 0 180)
			(size 0 0)
			(layers "B.Cu" "B.Mask" "B.Paste")
			(net "GND")
		)
	)
	(footprint ""
		(layer "B.Cu")
		(at 186.158886 -193.599816 -90)
		(property "Reference" "R818"
			(at 0 0 90)
			(layer "B.SilkS")
			(hide yes)
			(effects
				(font
					(size 1.27 1.27)
				)
				(justify mirror)
			)
		)
		(property "Value" ""
			(at 0 0 90)
			(layer "B.Fab")
			(effects
				(font
					(size 1.27 1.27)
				)
				(justify mirror)
			)
		)
		(duplicate_pad_numbers_are_jumpers no)
		(fp_line
			(start -0.7874 0.4064)
			(end 0.7874 0.4064)
			(stroke
				(width 0.1524)
				(type default)
			)
			(layer "B.SilkS")
		)
		(fp_line
			(start 0.7874 0.4064)
			(end 0.7874 -0.4064)
			(stroke
				(width 0.1524)
				(type default)
			)
			(layer "B.SilkS")
		)
		(fp_line
			(start -0.7874 -0.4064)
			(end -0.7874 0.4064)
			(stroke
				(width 0.1524)
				(type default)
			)
			(layer "B.SilkS")
		)
		(fp_line
			(start 0.7874 -0.4064)
			(end -0.7874 -0.4064)
			(stroke
				(width 0.1524)
				(type default)
			)
			(layer "B.SilkS")
		)
		(fp_line
			(start -0.67945 0.3048)
			(end -0.120396 0.3048)
			(stroke
				(width 0.1)
				(type default)
			)
			(layer "B.Fab")
		)
		(fp_line
			(start -0.120396 0.3048)
			(end -0.120396 0.2794)
			(stroke
				(width 0.1)
				(type default)
			)
			(layer "B.Fab")
		)
		(fp_line
			(start 0.12065 0.3048)
			(end 0.67945 0.3048)
			(stroke
				(width 0.1)
				(type default)
			)
			(layer "B.Fab")
		)
		(fp_line
			(start 0.67945 0.3048)
			(end 0.67945 -0.305054)
			(stroke
				(width 0.1)
				(type default)
			)
			(layer "B.Fab")
		)
		(fp_line
			(start -0.120396 0.2794)
			(end 0.12065 0.2794)
			(stroke
				(width 0.1)
				(type default)
			)
			(layer "B.Fab")
		)
		(fp_line
			(start 0.12065 0.2794)
			(end 0.12065 0.3048)
			(stroke
				(width 0.1)
				(type default)
			)
			(layer "B.Fab")
		)
		(fp_line
			(start -0.12065 -0.2794)
			(end -0.12065 -0.3048)
			(stroke
				(width 0.1)
				(type default)
			)
			(layer "B.Fab")
		)
		(fp_line
			(start 0.12065 -0.2794)
			(end -0.12065 -0.2794)
			(stroke
				(width 0.1)
				(type default)
			)
			(layer "B.Fab")
		)
		(fp_line
			(start -0.67945 -0.3048)
			(end -0.67945 0.3048)
			(stroke
				(width 0.1)
				(type default)
			)
			(layer "B.Fab")
		)
		(fp_line
			(start -0.12065 -0.3048)
			(end -0.67945 -0.3048)
			(stroke
				(width 0.1)
				(type default)
			)
			(layer "B.Fab")
		)
		(fp_line
			(start 0.12065 -0.305054)
			(end 0.12065 -0.2794)
			(stroke
				(width 0.1)
				(type default)
			)
			(layer "B.Fab")
		)
		(fp_line
			(start 0.67945 -0.305054)
			(end 0.12065 -0.305054)
			(stroke
				(width 0.1)
				(type default)
			)
			(layer "B.Fab")
		)
		(pad "1" smd circle
			(at 0.40005 0 90)
			(size 0 0)
			(layers "B.Cu" "B.Mask" "B.Paste")
			(net "RST_PLD_CPU1_DRAM_EF_N")
		)
		(pad "2" smd circle
			(at -0.40005 0 90)
			(size 0 0)
			(layers "B.Cu" "B.Mask" "B.Paste")
			(net "RST_M_EF_CPU1_FPGA_N")
		)
	)
	(footprint ""
		(layer "B.Cu")
		(at 212.612478 -193.42989)
		(property "Reference" "U22"
			(at 0.09398 2.04089 0)
			(unlocked yes)
			(layer "B.SilkS")
			(effects
				(font
					(size 0.7874 0.5842)
					(thickness 0.1524)
				)
				(justify mirror)
			)
		)
		(property "Value" ""
			(at 0 0 0)
			(layer "B.Fab")
			(effects
				(font
					(size 1.27 1.27)
				)
				(justify mirror)
			)
		)
		(duplicate_pad_numbers_are_jumpers no)
		(fp_line
			(start -1.7272 -1.1176)
			(end -1.7272 1.1176)
			(stroke
				(width 0.1524)
				(type default)
			)
			(layer "B.SilkS")
		)
		(fp_line
			(start -1.7272 -1.1176)
			(end -0.254 -1.1176)
			(stroke
				(width 0.1524)
				(type default)
			)
			(layer "B.SilkS")
		)
		(fp_line
			(start -1.7272 1.1176)
			(end 1.7272 1.1176)
			(stroke
				(width 0.1524)
				(type default)
			)
			(layer "B.SilkS")
		)
		(fp_line
			(start -0.254 -1.1176)
			(end 0 -0.7366)
			(stroke
				(width 0.1524)
				(type default)
			)
			(layer "B.SilkS")
		)
		(fp_line
			(start 0 -0.7366)
			(end 0.254 -1.1176)
			(stroke
				(width 0.1524)
				(type default)
			)
			(layer "B.SilkS")
		)
		(fp_line
			(start 0.254 -1.1176)
			(end 1.7272 -1.1176)
			(stroke
				(width 0.1524)
				(type default)
			)
			(layer "B.SilkS")
		)
		(fp_line
			(start 1.7272 1.1176)
			(end 1.7272 -1.1176)
			(stroke
				(width 0.1524)
				(type default)
			)
			(layer "B.SilkS")
		)
		(fp_poly
			(pts
				(xy 1.86436 -0.898906) (xy 2.177542 -1.05537) (xy 2.177542 -0.742442)
			)
			(stroke
				(width 0)
				(type default)
			)
			(fill yes)
			(layer "B.SilkS")
		)
		(fp_line
			(start -1.5748 -1.1176)
			(end 1.5748 -1.1176)
			(stroke
				(width 0.1)
				(type default)
			)
			(layer "B.Fab")
		)
		(fp_line
			(start -1.5748 1.1176)
			(end -1.5748 -1.1176)
			(stroke
				(width 0.1)
				(type default)
			)
			(layer "B.Fab")
		)
		(fp_line
			(start 1.5748 -1.1176)
			(end 1.5748 1.1176)
			(stroke
				(width 0.1)
				(type default)
			)
			(layer "B.Fab")
		)
		(fp_line
			(start 1.5748 1.1176)
			(end -1.5748 1.1176)
			(stroke
				(width 0.1)
				(type default)
			)
			(layer "B.Fab")
		)
		(fp_poly
			(pts
				(xy 1.9558 -0.649986) (xy 2.7178 -0.268986) (xy 2.7178 -1.030986)
			)
			(stroke
				(width 0)
				(type default)
			)
			(fill yes)
			(layer "B.Fab")
		)
		(pad "1" smd rect
			(at 0.999998 -0.649986 270)
			(size 0.3556 1.1176)
			(layers "B.Cu" "B.Mask" "B.Paste")
			(net "JTAG_CPU0_MUX_GTL_TDO")
		)
		(pad "2" smd rect
			(at 0.999998 0 270)
			(size 0.3556 1.1176)
			(layers "B.Cu" "B.Mask" "B.Paste")
			(net "GND")
		)
		(pad "3" smd rect
			(at 0.999998 0.649986 270)
			(size 0.3556 1.1176)
			(layers "B.Cu" "B.Mask" "B.Paste")
			(net "JTAG_CPU1_MUX_GTL_TDO")
		)
		(pad "4" smd rect
			(at -0.999998 0.649986 270)
			(size 0.3556 1.1176)
			(layers "B.Cu" "B.Mask" "B.Paste")
			(net "JTAG_MUX_QS_GTL_TDO")
		)
		(pad "5" smd rect
			(at -0.999998 0 270)
			(size 0.3556 1.1176)
			(layers "B.Cu" "B.Mask" "B.Paste")
			(net "P3V3_AUX")
		)
		(pad "6" smd rect
			(at -0.999998 -0.649986 270)
			(size 0.3556 1.1176)
			(layers "B.Cu" "B.Mask" "B.Paste")
			(net "FM_CPU1_SKTOCC_N")
		)
	)
	(footprint ""
		(layer "B.Cu")
		(at 158.825946 -321.554856 -90)
		(property "Reference" "C91"
			(at 0 0 90)
			(layer "B.SilkS")
			(hide yes)
			(effects
				(font
					(size 1.27 1.27)
				)
				(justify mirror)
			)
		)
		(property "Value" ""
			(at 0 0 90)
			(layer "B.Fab")
			(effects
				(font
					(size 1.27 1.27)
				)
				(justify mirror)
			)
		)
		(duplicate_pad_numbers_are_jumpers no)
		(fp_line
			(start -1.524 0.762)
			(end 1.524 0.762)
			(stroke
				(width 0.1524)
				(type default)
			)
			(layer "B.SilkS")
		)
		(fp_line
			(start 1.524 0.762)
			(end 1.524 -0.762)
			(stroke
				(width 0.1524)
				(type default)
			)
			(layer "B.SilkS")
		)
		(fp_line
			(start -1.524 -0.762)
			(end -1.524 0.762)
			(stroke
				(width 0.1524)
				(type default)
			)
			(layer "B.SilkS")
		)
		(fp_line
			(start 1.524 -0.762)
			(end -1.524 -0.762)
			(stroke
				(width 0.1524)
				(type default)
			)
			(layer "B.SilkS")
		)
		(fp_line
			(start -1.1049 0.724916)
			(end -1.1049 -0.724916)
			(stroke
				(width 0.1)
				(type default)
			)
			(layer "B.Fab")
		)
		(fp_line
			(start 1.1049 0.724916)
			(end -1.1049 0.724916)
			(stroke
				(width 0.1)
				(type default)
			)
			(layer "B.Fab")
		)
		(fp_line
			(start -1.1049 -0.724916)
			(end 1.1049 -0.724916)
			(stroke
				(width 0.1)
				(type default)
			)
			(layer "B.Fab")
		)
		(fp_line
			(start 1.1049 -0.724916)
			(end 1.1049 0.724916)
			(stroke
				(width 0.1)
				(type default)
			)
			(layer "B.Fab")
		)
		(pad "1" smd rect
			(at 0.889 0 270)
			(size 1.016 1.27)
			(layers "B.Cu" "B.Mask" "B.Paste")
			(net "P12V_S3_AUX_CPU1_NVDIMM")
		)
		(pad "2" smd rect
			(at -0.889 0 270)
			(size 1.016 1.27)
			(layers "B.Cu" "B.Mask" "B.Paste")
			(net "GND")
		)
	)
	(footprint ""
		(layer "B.Cu")
		(at 204.133958 -194.03441)
		(property "Reference" "C539"
			(at 0 0 0)
			(layer "B.SilkS")
			(hide yes)
			(effects
				(font
					(size 1.27 1.27)
				)
				(justify mirror)
			)
		)
		(property "Value" ""
			(at 0 0 0)
			(layer "B.Fab")
			(effects
				(font
					(size 1.27 1.27)
				)
				(justify mirror)
			)
		)
		(duplicate_pad_numbers_are_jumpers no)
		(fp_line
			(start -0.7874 -0.4064)
			(end -0.7874 0.4064)
			(stroke
				(width 0.1524)
				(type default)
			)
			(layer "B.SilkS")
		)
		(fp_line
			(start -0.7874 0.4064)
			(end 0.7874 0.4064)
			(stroke
				(width 0.1524)
				(type default)
			)
			(layer "B.SilkS")
		)
		(fp_line
			(start 0.7874 -0.4064)
			(end -0.7874 -0.4064)
			(stroke
				(width 0.1524)
				(type default)
			)
			(layer "B.SilkS")
		)
		(fp_line
			(start 0.7874 0.4064)
			(end 0.7874 -0.4064)
			(stroke
				(width 0.1524)
				(type default)
			)
			(layer "B.SilkS")
		)
		(fp_line
			(start -0.67945 -0.3048)
			(end -0.67945 0.3048)
			(stroke
				(width 0.1)
				(type default)
			)
			(layer "B.Fab")
		)
		(fp_line
			(start -0.67945 0.3048)
			(end -0.120396 0.3048)
			(stroke
				(width 0.1)
				(type default)
			)
			(layer "B.Fab")
		)
		(fp_line
			(start -0.12065 -0.3048)
			(end -0.67945 -0.3048)
			(stroke
				(width 0.1)
				(type default)
			)
			(layer "B.Fab")
		)
		(fp_line
			(start -0.12065 -0.2794)
			(end -0.12065 -0.3048)
			(stroke
				(width 0.1)
				(type default)
			)
			(layer "B.Fab")
		)
		(fp_line
			(start -0.120396 0.2794)
			(end 0.12065 0.2794)
			(stroke
				(width 0.1)
				(type default)
			)
			(layer "B.Fab")
		)
		(fp_line
			(start -0.120396 0.3048)
			(end -0.120396 0.2794)
			(stroke
				(width 0.1)
				(type default)
			)
			(layer "B.Fab")
		)
		(fp_line
			(start 0.12065 -0.305054)
			(end 0.12065 -0.2794)
			(stroke
				(width 0.1)
				(type default)
			)
			(layer "B.Fab")
		)
		(fp_line
			(start 0.12065 -0.2794)
			(end -0.12065 -0.2794)
			(stroke
				(width 0.1)
				(type default)
			)
			(layer "B.Fab")
		)
		(fp_line
			(start 0.12065 0.2794)
			(end 0.12065 0.3048)
			(stroke
				(width 0.1)
				(type default)
			)
			(layer "B.Fab")
		)
		(fp_line
			(start 0.12065 0.3048)
			(end 0.67945 0.3048)
			(stroke
				(width 0.1)
				(type default)
			)
			(layer "B.Fab")
		)
		(fp_line
			(start 0.67945 -0.305054)
			(end 0.12065 -0.305054)
			(stroke
				(width 0.1)
				(type default)
			)
			(layer "B.Fab")
		)
		(fp_line
			(start 0.67945 0.3048)
			(end 0.67945 -0.305054)
			(stroke
				(width 0.1)
				(type default)
			)
			(layer "B.Fab")
		)
		(pad "1" smd circle
			(at 0.40005 0 180)
			(size 0 0)
			(layers "B.Cu" "B.Mask" "B.Paste")
			(net "P3V3_AUX")
		)
		(pad "2" smd circle
			(at -0.40005 0 180)
			(size 0 0)
			(layers "B.Cu" "B.Mask" "B.Paste")
			(net "GND")
		)
	)
)
